(kicad_pcb
	(version 20260206)
	(generator "pcbnew")
	(generator_version "10.0")
	(general
		(thickness 1.6)
		(legacy_teardrops no)
	)
	(paper "A4")
	(title_block
		(title "15969-1a.1015WZS0858.brd")
		(comment 1 "Tioga Pass / footprint 37 of 295 (GF2), pads 1-104 of 200")
	)
	(layers
		(0 "F.Cu" signal "TOP")
		(4 "In1.Cu" signal "L2GND")
		(6 "In2.Cu" signal "L3")
		(8 "In3.Cu" signal "L4")
		(10 "In4.Cu" signal "L5GND")
		(2 "B.Cu" signal "BOTTOM")
		(9 "F.Adhes" user "F.Adhesive")
		(11 "B.Adhes" user "B.Adhesive")
		(13 "F.Paste" user "Package Geometry/Pastemask Top")
		(15 "B.Paste" user "Package Geometry/Pastemask Bottom")
		(5 "F.SilkS" user "Ref Des/Silkscreen Top")
		(7 "B.SilkS" user "Ref Des/Silkscreen Bottom")
		(1 "F.Mask" user "Board Geometry/Soldermask Top")
		(3 "B.Mask" user "Board Geometry/Soldermask Bottom")
		(17 "Dwgs.User" user "User.Drawings")
		(19 "Cmts.User" user "User.Comments")
		(21 "Eco1.User" user "User.Eco1")
		(23 "Eco2.User" user "User.Eco2")
		(25 "Edge.Cuts" user "Board Geometry/Outline")
		(27 "Margin" user)
		(31 "F.CrtYd" user "Package Geometry/Place Bound Top")
		(29 "B.CrtYd" user "Package Geometry/Place Bound Bottom")
		(35 "F.Fab" user "Ref Des/Assembly Top")
		(33 "B.Fab" user "Ref Des/Assembly Bottom")
	)
	(footprint ""
		(layer "F.Cu")
		(at 42.3799 13.530072)
		(property "Reference" "GF2"
			(at 0 0 0)
			(layer "F.SilkS")
			(hide yes)
			(effects
				(font
					(size 1.27 1.27)
				)
			)
		)
		(property "Value" "GF-200P-11-GP"
			(at 58.674 -9.3472 0)
			(unlocked yes)
			(layer "F.Fab")
			(hide yes)
			(effects
				(font
					(size 1.016 1.016)
					(thickness 0.1524)
				)
			)
		)
		(property "Device Type" "GF-200P-11"
			(at 58.674 -10.8712 0)
			(unlocked yes)
			(layer "F.Fab")
			(hide yes)
			(effects
				(font
					(size 1.016 1.016)
					(thickness 0.1524)
				)
			)
		)
		(duplicate_pad_numbers_are_jumpers no)
		(pad "1" smd rect
			(at -26.800048 -1.397)
			(size 0.5588 2.794)
			(layers "F.Cu" "F.Mask" "F.Paste")
			(net "P12V")
		)
		(pad "2" smd rect
			(at -26.800048 -1.016)
			(size 0.5588 2.794)
			(drill
				(offset 0 -0.381)
			)
			(layers "F.Cu" "F.Mask" "F.Paste")
			(net "P12V")
		)
		(pad "3" smd rect
			(at -25.999948 -1.397)
			(size 0.5588 2.794)
			(layers "F.Cu" "F.Mask" "F.Paste")
			(net "P12V")
		)
		(pad "4" smd rect
			(at -25.999948 -1.016)
			(size 0.5588 2.794)
			(drill
				(offset 0 -0.381)
			)
			(layers "F.Cu" "F.Mask" "F.Paste")
			(net "P12V")
		)
		(pad "5" smd rect
			(at -25.200102 -1.397)
			(size 0.5588 2.794)
			(layers "F.Cu" "F.Mask" "F.Paste")
			(net "P12V")
		)
		(pad "6" smd rect
			(at -25.200102 -1.016)
			(size 0.5588 2.794)
			(drill
				(offset 0 -0.381)
			)
			(layers "F.Cu" "F.Mask" "F.Paste")
			(net "P12V")
		)
		(pad "7" smd rect
			(at -24.400002 -1.397)
			(size 0.5588 2.794)
			(layers "F.Cu" "F.Mask" "F.Paste")
			(net "P12V")
		)
		(pad "8" smd rect
			(at -24.400002 -1.016)
			(size 0.5588 2.794)
			(drill
				(offset 0 -0.381)
			)
			(layers "F.Cu" "F.Mask" "F.Paste")
			(net "P12V")
		)
		(pad "9" smd rect
			(at -23.599902 -1.397)
			(size 0.5588 2.794)
			(layers "F.Cu" "F.Mask" "F.Paste")
			(net "P12V")
		)
		(pad "10" smd rect
			(at -23.599902 -1.016)
			(size 0.5588 2.794)
			(drill
				(offset 0 -0.381)
			)
			(layers "F.Cu" "F.Mask" "F.Paste")
			(net "P12V")
		)
		(pad "11" smd rect
			(at -22.800056 -1.397)
			(size 0.5588 2.794)
			(layers "F.Cu" "F.Mask" "F.Paste")
			(net "P12V")
		)
		(pad "12" smd rect
			(at -22.800056 -1.016)
			(size 0.5588 2.794)
			(drill
				(offset 0 -0.381)
			)
			(layers "F.Cu" "F.Mask" "F.Paste")
			(net "P12V")
		)
		(pad "13" smd rect
			(at -21.999956 -1.397)
			(size 0.5588 2.794)
			(layers "F.Cu" "F.Mask" "F.Paste")
			(net "GND")
		)
		(pad "14" smd rect
			(at -21.999956 -1.016)
			(size 0.5588 2.794)
			(drill
				(offset 0 -0.381)
			)
			(layers "F.Cu" "F.Mask" "F.Paste")
			(net "GND")
		)
		(pad "15" smd rect
			(at -21.20011 -1.397)
			(size 0.5588 2.794)
			(layers "F.Cu" "F.Mask" "F.Paste")
			(net "SMB_SLOTX24_STBY_LVC3_SDA_R2")
		)
		(pad "16" smd rect
			(at -21.20011 -1.016)
			(size 0.5588 2.794)
			(drill
				(offset 0 -0.381)
			)
			(layers "F.Cu" "F.Mask" "F.Paste")
			(net "IRQ_OOB_MGMT_RISER_ALERT_N")
		)
		(pad "17" smd rect
			(at -20.40001 -1.397)
			(size 0.5588 2.794)
			(layers "F.Cu" "F.Mask" "F.Paste")
			(net "SMB_SLOTX24_STBY_LVC3_SCL_R2")
		)
		(pad "18" smd rect
			(at -20.40001 -1.016)
			(size 0.5588 2.794)
			(drill
				(offset 0 -0.381)
			)
			(layers "F.Cu" "F.Mask" "F.Paste")
			(net "FM_SLT_CFG1")
		)
		(pad "19" smd rect
			(at -19.59991 -1.397)
			(size 0.5588 2.794)
			(layers "F.Cu" "F.Mask" "F.Paste")
			(net "FM_SLT_CFG0")
		)
		(pad "20" smd rect
			(at -19.59991 -1.016)
			(size 0.5588 2.794)
			(drill
				(offset 0 -0.381)
			)
			(layers "F.Cu" "F.Mask" "F.Paste")
			(net "FM_PWRBRK_SLOT_N")
		)
		(pad "21" smd rect
			(at -18.800064 -1.397)
			(size 0.5588 2.794)
			(layers "F.Cu" "F.Mask" "F.Paste")
			(net "P3V3_MB")
		)
		(pad "22" smd rect
			(at -18.800064 -1.016)
			(size 0.5588 2.794)
			(drill
				(offset 0 -0.381)
			)
			(layers "F.Cu" "F.Mask" "F.Paste")
			(net "P3V3_MB")
		)
		(pad "23" smd rect
			(at -17.999964 -1.397)
			(size 0.5588 2.794)
			(layers "F.Cu" "F.Mask" "F.Paste")
			(net "P3V3_MB")
		)
		(pad "24" smd rect
			(at -17.999964 -1.016)
			(size 0.5588 2.794)
			(drill
				(offset 0 -0.381)
			)
			(layers "F.Cu" "F.Mask" "F.Paste")
			(net "P3V3_MB")
		)
		(pad "25" smd rect
			(at -17.200118 -1.397)
			(size 0.5588 2.794)
			(layers "F.Cu" "F.Mask" "F.Paste")
			(net "P3V3_STBY")
		)
		(pad "26" smd rect
			(at -17.200118 -1.016)
			(size 0.5588 2.794)
			(drill
				(offset 0 -0.381)
			)
			(layers "F.Cu" "F.Mask" "F.Paste")
			(net "GND")
		)
		(pad "27" smd rect
			(at -16.400018 -1.397)
			(size 0.5588 2.794)
			(layers "F.Cu" "F.Mask" "F.Paste")
			(net "SMB_PCH_ALERT_R_N")
		)
		(pad "28" smd rect
			(at -16.400018 -1.016)
			(size 0.5588 2.794)
			(drill
				(offset 0 -0.381)
			)
			(layers "F.Cu" "F.Mask" "F.Paste")
			(net "FM_PE_SLOTX24_WAKE_N")
		)
		(pad "29" smd rect
			(at -15.599918 -1.397)
			(size 0.5588 2.794)
			(layers "F.Cu" "F.Mask" "F.Paste")
			(net "PERST_N")
		)
		(pad "30" smd rect
			(at -15.599918 -1.016)
			(size 0.5588 2.794)
			(drill
				(offset 0 -0.381)
			)
			(layers "F.Cu" "F.Mask" "F.Paste")
			(net "SMB_HOST_STBY_LVC3_SDA_R5")
		)
		(pad "31" smd rect
			(at -14.800072 -1.397)
			(size 0.5588 2.794)
			(layers "F.Cu" "F.Mask" "F.Paste")
			(net "GND")
		)
		(pad "32" smd rect
			(at -14.800072 -1.016)
			(size 0.5588 2.794)
			(drill
				(offset 0 -0.381)
			)
			(layers "F.Cu" "F.Mask" "F.Paste")
			(net "SMB_HOST_STBY_LVC3_SCL_R5")
		)
		(pad "33" smd rect
			(at -13.999972 -1.397)
			(size 0.5588 2.794)
			(layers "F.Cu" "F.Mask" "F.Paste")
			(net "CLK_100M_PCH_SLOTX24_S5_DP")
		)
		(pad "34" smd rect
			(at -13.999972 -1.016)
			(size 0.5588 2.794)
			(drill
				(offset 0 -0.381)
			)
			(layers "F.Cu" "F.Mask" "F.Paste")
			(net "GND")
		)
		(pad "35" smd rect
			(at -13.200126 -1.397)
			(size 0.5588 2.794)
			(layers "F.Cu" "F.Mask" "F.Paste")
			(net "CLK_100M_PCH_SLOTX24_S5_DN")
		)
		(pad "36" smd rect
			(at -13.200126 -1.016)
			(size 0.5588 2.794)
			(drill
				(offset 0 -0.381)
			)
			(layers "F.Cu" "F.Mask" "F.Paste")
			(net "CLK_100M_PCH_SLOTX24_S4_DP")
		)
		(pad "37" smd rect
			(at -12.400026 -1.397)
			(size 0.5588 2.794)
			(layers "F.Cu" "F.Mask" "F.Paste")
			(net "GND")
		)
		(pad "38" smd rect
			(at -12.400026 -1.016)
			(size 0.5588 2.794)
			(drill
				(offset 0 -0.381)
			)
			(layers "F.Cu" "F.Mask" "F.Paste")
			(net "CLK_100M_PCH_SLOTX24_S4_DN")
		)
		(pad "39" smd rect
			(at -11.599926 -1.397)
			(size 0.5588 2.794)
			(layers "F.Cu" "F.Mask" "F.Paste")
			(net "Net_107")
		)
		(pad "40" smd rect
			(at -11.599926 -1.016)
			(size 0.5588 2.794)
			(drill
				(offset 0 -0.381)
			)
			(layers "F.Cu" "F.Mask" "F.Paste")
			(net "GND")
		)
		(pad "41" smd rect
			(at -10.80008 -1.397)
			(size 0.5588 2.794)
			(layers "F.Cu" "F.Mask" "F.Paste")
			(net "Net_106")
		)
		(pad "42" smd rect
			(at -10.80008 -1.016)
			(size 0.5588 2.794)
			(drill
				(offset 0 -0.381)
			)
			(layers "F.Cu" "F.Mask" "F.Paste")
			(net "Net_109")
		)
		(pad "43" smd rect
			(at -9.99998 -1.397)
			(size 0.5588 2.794)
			(layers "F.Cu" "F.Mask" "F.Paste")
			(net "GND")
		)
		(pad "44" smd rect
			(at -9.99998 -1.016)
			(size 0.5588 2.794)
			(drill
				(offset 0 -0.381)
			)
			(layers "F.Cu" "F.Mask" "F.Paste")
			(net "Net_108")
		)
		(pad "45" smd rect
			(at -9.19988 -1.397)
			(size 0.5588 2.794)
			(layers "F.Cu" "F.Mask" "F.Paste")
			(net "Net_113")
		)
		(pad "46" smd rect
			(at -9.19988 -1.016)
			(size 0.5588 2.794)
			(drill
				(offset 0 -0.381)
			)
			(layers "F.Cu" "F.Mask" "F.Paste")
			(net "GND")
		)
		(pad "47" smd rect
			(at -8.400034 -1.397)
			(size 0.5588 2.794)
			(layers "F.Cu" "F.Mask" "F.Paste")
			(net "Net_112")
		)
		(pad "48" smd rect
			(at -8.400034 -1.016)
			(size 0.5588 2.794)
			(drill
				(offset 0 -0.381)
			)
			(layers "F.Cu" "F.Mask" "F.Paste")
			(net "Net_111")
		)
		(pad "49" smd rect
			(at -7.599934 -1.397)
			(size 0.5588 2.794)
			(layers "F.Cu" "F.Mask" "F.Paste")
			(net "GND")
		)
		(pad "50" smd rect
			(at -7.599934 -1.016)
			(size 0.5588 2.794)
			(drill
				(offset 0 -0.381)
			)
			(layers "F.Cu" "F.Mask" "F.Paste")
			(net "Net_110")
		)
		(pad "51" smd rect
			(at -6.800088 -1.397)
			(size 0.5588 2.794)
			(layers "F.Cu" "F.Mask" "F.Paste")
			(net "P3E_CPU0_PE1_PCH_CON_TXP<15>")
		)
		(pad "52" smd rect
			(at -6.800088 -1.016)
			(size 0.5588 2.794)
			(drill
				(offset 0 -0.381)
			)
			(layers "F.Cu" "F.Mask" "F.Paste")
			(net "GND")
		)
		(pad "53" smd rect
			(at -5.999988 -1.397)
			(size 0.5588 2.794)
			(layers "F.Cu" "F.Mask" "F.Paste")
			(net "P3E_CPU0_PE1_PCH_CON_TXN<15>")
		)
		(pad "54" smd rect
			(at -5.999988 -1.016)
			(size 0.5588 2.794)
			(drill
				(offset 0 -0.381)
			)
			(layers "F.Cu" "F.Mask" "F.Paste")
			(net "P3E_CPU0_PE1_PCH_CON_RXP<15>")
		)
		(pad "55" smd rect
			(at -5.199888 -1.397)
			(size 0.5588 2.794)
			(layers "F.Cu" "F.Mask" "F.Paste")
			(net "GND")
		)
		(pad "56" smd rect
			(at -5.199888 -1.016)
			(size 0.5588 2.794)
			(drill
				(offset 0 -0.381)
			)
			(layers "F.Cu" "F.Mask" "F.Paste")
			(net "P3E_CPU0_PE1_PCH_CON_RXN<15>")
		)
		(pad "57" smd rect
			(at -4.400042 -1.397)
			(size 0.5588 2.794)
			(layers "F.Cu" "F.Mask" "F.Paste")
			(net "P3E_CPU0_PE1_PCH_CON_TXP<14>")
		)
		(pad "58" smd rect
			(at -4.400042 -1.016)
			(size 0.5588 2.794)
			(drill
				(offset 0 -0.381)
			)
			(layers "F.Cu" "F.Mask" "F.Paste")
			(net "GND")
		)
		(pad "59" smd rect
			(at -3.599942 -1.397)
			(size 0.5588 2.794)
			(layers "F.Cu" "F.Mask" "F.Paste")
			(net "P3E_CPU0_PE1_PCH_CON_TXN<14>")
		)
		(pad "60" smd rect
			(at -3.599942 -1.016)
			(size 0.5588 2.794)
			(drill
				(offset 0 -0.381)
			)
			(layers "F.Cu" "F.Mask" "F.Paste")
			(net "P3E_CPU0_PE1_PCH_CON_RXP<14>")
		)
		(pad "61" smd rect
			(at -2.800096 -1.397)
			(size 0.5588 2.794)
			(layers "F.Cu" "F.Mask" "F.Paste")
			(net "GND")
		)
		(pad "62" smd rect
			(at -2.800096 -1.016)
			(size 0.5588 2.794)
			(drill
				(offset 0 -0.381)
			)
			(layers "F.Cu" "F.Mask" "F.Paste")
			(net "P3E_CPU0_PE1_PCH_CON_RXN<14>")
		)
		(pad "63" smd rect
			(at -1.999996 -1.397)
			(size 0.5588 2.794)
			(layers "F.Cu" "F.Mask" "F.Paste")
			(net "Net_116")
		)
		(pad "64" smd rect
			(at -1.999996 -1.016)
			(size 0.5588 2.794)
			(drill
				(offset 0 -0.381)
			)
			(layers "F.Cu" "F.Mask" "F.Paste")
			(net "GND")
		)
		(pad "65" smd rect
			(at 1.999996 -1.397)
			(size 0.5588 2.794)
			(layers "F.Cu" "F.Mask" "F.Paste")
			(net "GND")
		)
		(pad "66" smd rect
			(at 1.999996 -1.016)
			(size 0.5588 2.794)
			(drill
				(offset 0 -0.381)
			)
			(layers "F.Cu" "F.Mask" "F.Paste")
			(net "Net_117")
		)
		(pad "67" smd rect
			(at 2.800096 -1.397)
			(size 0.5588 2.794)
			(layers "F.Cu" "F.Mask" "F.Paste")
			(net "P3E_CPU0_PE1_PCH_CON_TXP<13>")
		)
		(pad "68" smd rect
			(at 2.800096 -1.016)
			(size 0.5588 2.794)
			(drill
				(offset 0 -0.381)
			)
			(layers "F.Cu" "F.Mask" "F.Paste")
			(net "GND")
		)
		(pad "69" smd rect
			(at 3.599942 -1.397)
			(size 0.5588 2.794)
			(layers "F.Cu" "F.Mask" "F.Paste")
			(net "P3E_CPU0_PE1_PCH_CON_TXN<13>")
		)
		(pad "70" smd rect
			(at 3.599942 -1.016)
			(size 0.5588 2.794)
			(drill
				(offset 0 -0.381)
			)
			(layers "F.Cu" "F.Mask" "F.Paste")
			(net "P3E_CPU0_PE1_PCH_CON_RXP<13>")
		)
		(pad "71" smd rect
			(at 4.400042 -1.397)
			(size 0.5588 2.794)
			(layers "F.Cu" "F.Mask" "F.Paste")
			(net "GND")
		)
		(pad "72" smd rect
			(at 4.400042 -1.016)
			(size 0.5588 2.794)
			(drill
				(offset 0 -0.381)
			)
			(layers "F.Cu" "F.Mask" "F.Paste")
			(net "P3E_CPU0_PE1_PCH_CON_RXN<13>")
		)
		(pad "73" smd rect
			(at 5.199888 -1.397)
			(size 0.5588 2.794)
			(layers "F.Cu" "F.Mask" "F.Paste")
			(net "P3E_CPU0_PE1_PCH_CON_TXP<12>")
		)
		(pad "74" smd rect
			(at 5.199888 -1.016)
			(size 0.5588 2.794)
			(drill
				(offset 0 -0.381)
			)
			(layers "F.Cu" "F.Mask" "F.Paste")
			(net "GND")
		)
		(pad "75" smd rect
			(at 5.999988 -1.397)
			(size 0.5588 2.794)
			(layers "F.Cu" "F.Mask" "F.Paste")
			(net "P3E_CPU0_PE1_PCH_CON_TXN<12>")
		)
		(pad "76" smd rect
			(at 5.999988 -1.016)
			(size 0.5588 2.794)
			(drill
				(offset 0 -0.381)
			)
			(layers "F.Cu" "F.Mask" "F.Paste")
			(net "P3E_CPU0_PE1_PCH_CON_RXP<12>")
		)
		(pad "77" smd rect
			(at 6.800088 -1.397)
			(size 0.5588 2.794)
			(layers "F.Cu" "F.Mask" "F.Paste")
			(net "GND")
		)
		(pad "78" smd rect
			(at 6.800088 -1.016)
			(size 0.5588 2.794)
			(drill
				(offset 0 -0.381)
			)
			(layers "F.Cu" "F.Mask" "F.Paste")
			(net "P3E_CPU0_PE1_PCH_CON_RXN<12>")
		)
		(pad "79" smd rect
			(at 7.599934 -1.397)
			(size 0.5588 2.794)
			(layers "F.Cu" "F.Mask" "F.Paste")
			(net "P3E_CPU0_PE1_PCH_CON_TXP<11>")
		)
		(pad "80" smd rect
			(at 7.599934 -1.016)
			(size 0.5588 2.794)
			(drill
				(offset 0 -0.381)
			)
			(layers "F.Cu" "F.Mask" "F.Paste")
			(net "GND")
		)
		(pad "81" smd rect
			(at 8.400034 -1.397)
			(size 0.5588 2.794)
			(layers "F.Cu" "F.Mask" "F.Paste")
			(net "P3E_CPU0_PE1_PCH_CON_TXN<11>")
		)
		(pad "82" smd rect
			(at 8.400034 -1.016)
			(size 0.5588 2.794)
			(drill
				(offset 0 -0.381)
			)
			(layers "F.Cu" "F.Mask" "F.Paste")
			(net "P3E_CPU0_PE1_PCH_CON_RXP<11>")
		)
		(pad "83" smd rect
			(at 9.19988 -1.397)
			(size 0.5588 2.794)
			(layers "F.Cu" "F.Mask" "F.Paste")
			(net "GND")
		)
		(pad "84" smd rect
			(at 9.19988 -1.016)
			(size 0.5588 2.794)
			(drill
				(offset 0 -0.381)
			)
			(layers "F.Cu" "F.Mask" "F.Paste")
			(net "P3E_CPU0_PE1_PCH_CON_RXN<11>")
		)
		(pad "85" smd rect
			(at 9.99998 -1.397)
			(size 0.5588 2.794)
			(layers "F.Cu" "F.Mask" "F.Paste")
			(net "P3E_CPU0_PE1_PCH_CON_TXP<10>")
		)
		(pad "86" smd rect
			(at 9.99998 -1.016)
			(size 0.5588 2.794)
			(drill
				(offset 0 -0.381)
			)
			(layers "F.Cu" "F.Mask" "F.Paste")
			(net "GND")
		)
		(pad "87" smd rect
			(at 10.80008 -1.397)
			(size 0.5588 2.794)
			(layers "F.Cu" "F.Mask" "F.Paste")
			(net "P3E_CPU0_PE1_PCH_CON_TXN<10>")
		)
		(pad "88" smd rect
			(at 10.80008 -1.016)
			(size 0.5588 2.794)
			(drill
				(offset 0 -0.381)
			)
			(layers "F.Cu" "F.Mask" "F.Paste")
			(net "P3E_CPU0_PE1_PCH_CON_RXP<10>")
		)
		(pad "89" smd rect
			(at 11.599926 -1.397)
			(size 0.5588 2.794)
			(layers "F.Cu" "F.Mask" "F.Paste")
			(net "GND")
		)
		(pad "90" smd rect
			(at 11.599926 -1.016)
			(size 0.5588 2.794)
			(drill
				(offset 0 -0.381)
			)
			(layers "F.Cu" "F.Mask" "F.Paste")
			(net "P3E_CPU0_PE1_PCH_CON_RXN<10>")
		)
		(pad "91" smd rect
			(at 12.400026 -1.397)
			(size 0.5588 2.794)
			(layers "F.Cu" "F.Mask" "F.Paste")
			(net "P3E_CPU0_PE1_PCH_CON_TXP<9>")
		)
		(pad "92" smd rect
			(at 12.400026 -1.016)
			(size 0.5588 2.794)
			(drill
				(offset 0 -0.381)
			)
			(layers "F.Cu" "F.Mask" "F.Paste")
			(net "GND")
		)
		(pad "93" smd rect
			(at 13.200126 -1.397)
			(size 0.5588 2.794)
			(layers "F.Cu" "F.Mask" "F.Paste")
			(net "P3E_CPU0_PE1_PCH_CON_TXN<9>")
		)
		(pad "94" smd rect
			(at 13.200126 -1.016)
			(size 0.5588 2.794)
			(drill
				(offset 0 -0.381)
			)
			(layers "F.Cu" "F.Mask" "F.Paste")
			(net "P3E_CPU0_PE1_PCH_CON_RXP<9>")
		)
		(pad "95" smd rect
			(at 13.999972 -1.397)
			(size 0.5588 2.794)
			(layers "F.Cu" "F.Mask" "F.Paste")
			(net "GND")
		)
		(pad "96" smd rect
			(at 13.999972 -1.016)
			(size 0.5588 2.794)
			(drill
				(offset 0 -0.381)
			)
			(layers "F.Cu" "F.Mask" "F.Paste")
			(net "P3E_CPU0_PE1_PCH_CON_RXN<9>")
		)
		(pad "97" smd rect
			(at 14.800072 -1.397)
			(size 0.5588 2.794)
			(layers "F.Cu" "F.Mask" "F.Paste")
			(net "P3E_CPU0_PE1_PCH_CON_TXP<8>")
		)
		(pad "98" smd rect
			(at 14.800072 -1.016)
			(size 0.5588 2.794)
			(drill
				(offset 0 -0.381)
			)
			(layers "F.Cu" "F.Mask" "F.Paste")
			(net "GND")
		)
		(pad "99" smd rect
			(at 15.599918 -1.397)
			(size 0.5588 2.794)
			(layers "F.Cu" "F.Mask" "F.Paste")
			(net "P3E_CPU0_PE1_PCH_CON_TXN<8>")
		)
		(pad "100" smd rect
			(at 15.599918 -1.016)
			(size 0.5588 2.794)
			(drill
				(offset 0 -0.381)
			)
			(layers "F.Cu" "F.Mask" "F.Paste")
			(net "P3E_CPU0_PE1_PCH_CON_RXP<8>")
		)
		(pad "101" smd rect
			(at 16.400018 -1.397)
			(size 0.5588 2.794)
			(layers "F.Cu" "F.Mask" "F.Paste")
			(net "GND")
		)
		(pad "102" smd rect
			(at 16.400018 -1.016)
			(size 0.5588 2.794)
			(drill
				(offset 0 -0.381)
			)
			(layers "F.Cu" "F.Mask" "F.Paste")
			(net "P3E_CPU0_PE1_PCH_CON_RXN<8>")
		)
		(pad "103" smd rect
			(at 17.200118 -1.397)
			(size 0.5588 2.794)
			(layers "F.Cu" "F.Mask" "F.Paste")
			(net "P3E_CPU0_PE1_SS_C_TXP<7>")
		)
		(pad "104" smd rect
			(at 17.200118 -1.016)
			(size 0.5588 2.794)
			(drill
				(offset 0 -0.381)
			)
			(layers "F.Cu" "F.Mask" "F.Paste")
			(net "GND")
		)
	)
)
